# SA800U (Snapdragon 845) Baseboard — assets/stackup.csv
Name;Type;Material;Thickness[mm];Constant
F.Mask;Top Solder Mask;;0.01;
F.Cu;copper;;0.035;
dielectric 1;core;FR4;0.274;4.5
In1.Cu;copper;;0.035;
dielectric 2;prepreg;FR4;0.274;4.5
In2.Cu;copper;;0.035;
dielectric 3;core;FR4;0.274;4.5
In3.Cu;copper;;0.035;
dielectric 4;prepreg;FR4;0.274;4.5
In4.Cu;copper;;0.035;
dielectric 5;core;FR4;0.274;4.5
B.Cu;copper;;0.035;
B.Mask;Bottom Solder Mask;;0.01;
